# T6G (Grand Teton) — schematic netlist excerpt (pin names and nets, part order shuffled) for the footprints in the layout excerpt that follows; sources: Cadence DE-HDL packaged netlist, KiCad conversion of 04192023_DAF0TMB3IC0_F0TG_MB_C_brd_V02_OCP.brd

R140  Q_RES  0 5% EMPTY  pkg 0402LF  page 160 : A = SMB_CPU0_CPU1_APML_SCL ; B = SMB_CPU0_CPU1_APML_BUF1_SCL
PC469  Q_CAP  470PF 50V 10% X7R  pkg 0402  page 193 : A = PVDDCR_CPU0_P0_TEMP0 ; B = GND
R688  Q_RES  33.2 1% CHIP  pkg 0201LF  page 311 : A = SMB_RT_CPU0_P3_ROM_R_SDA ; B = SMB_RT_CPU0_P3_ROM_SDA

(kicad_pcb
	(version 20260206)
	(generator "pcbnew")
	(generator_version "10.0")
	(general
		(thickness 1.6)
		(legacy_teardrops no)
	)
	(paper "A4")
	(title_block
		(title "04192023_DAF0TMB3IC0_F0TG_MB_C_brd_V02_OCP.brd")
		(comment 1 "Grand Teton / footprints 5729-5731 of 8354")
	)
	(layers
		(0 "F.Cu" signal "TOP")
		(4 "In1.Cu" signal "GND")
		(6 "In2.Cu" signal "IN1")
		(8 "In3.Cu" signal "GND1")
		(10 "In4.Cu" signal "IN2")
		(12 "In5.Cu" signal "GND2")
		(14 "In6.Cu" signal "IN3")
		(16 "In7.Cu" signal "GND3")
		(18 "In8.Cu" signal "VCC")
		(20 "In9.Cu" signal "VCC1")
		(22 "In10.Cu" signal "GND4")
		(24 "In11.Cu" signal "IN4")
		(26 "In12.Cu" signal "GND5")
		(28 "In13.Cu" signal "IN5")
		(30 "In14.Cu" signal "GND6")
		(32 "In15.Cu" signal "IN6")
		(34 "In16.Cu" signal "GND7")
		(2 "B.Cu" signal "BOTTOM")
		(9 "F.Adhes" user "F.Adhesive")
		(11 "B.Adhes" user "B.Adhesive")
		(13 "F.Paste" user "Package Geometry/Pastemask Top")
		(15 "B.Paste" user "Package Geometry/Pastemask Bottom")
		(5 "F.SilkS" user "Ref Des/Silkscreen Top")
		(7 "B.SilkS" user "Ref Des/Silkscreen Bottom")
		(1 "F.Mask" user "Board Geometry/Soldermask Top")
		(3 "B.Mask" user "Board Geometry/Soldermask Bottom")
		(17 "Dwgs.User" user "User.Drawings")
		(19 "Cmts.User" user "User.Comments")
		(21 "Eco1.User" user "User.Eco1")
		(23 "Eco2.User" user "User.Eco2")
		(25 "Edge.Cuts" user "Board Geometry/Outline")
		(27 "Margin" user)
		(31 "F.CrtYd" user "Package Geometry/Place Bound Top")
		(29 "B.CrtYd" user "Package Geometry/Place Bound Bottom")
		(35 "F.Fab" user "Ref Des/Assembly Top")
		(33 "B.Fab" user "Ref Des/Assembly Bottom")
	)
	(footprint ""
		(layer "B.Cu")
		(at 384.113278 -141.218158 180)
		(property "Reference" "PC469"
			(at 0 0 0)
			(layer "B.SilkS")
			(hide yes)
			(effects
				(font
					(size 1.27 1.27)
				)
				(justify mirror)
			)
		)
		(property "Value" ""
			(at 0 0 0)
			(layer "B.Fab")
			(effects
				(font
					(size 1.27 1.27)
				)
				(justify mirror)
			)
		)
		(duplicate_pad_numbers_are_jumpers no)
		(fp_line
			(start 0.7874 0.4064)
			(end 0.7874 -0.4064)
			(stroke
				(width 0.1524)
				(type default)
			)
			(layer "B.SilkS")
		)
		(fp_line
			(start 0.7874 -0.4064)
			(end -0.7874 -0.4064)
			(stroke
				(width 0.1524)
				(type default)
			)
			(layer "B.SilkS")
		)
		(fp_line
			(start -0.7874 0.4064)
			(end 0.7874 0.4064)
			(stroke
				(width 0.1524)
				(type default)
			)
			(layer "B.SilkS")
		)
		(fp_line
			(start -0.7874 -0.4064)
			(end -0.7874 0.4064)
			(stroke
				(width 0.1524)
				(type default)
			)
			(layer "B.SilkS")
		)
		(fp_line
			(start 0.67945 0.3048)
			(end 0.67945 -0.305054)
			(stroke
				(width 0.1)
				(type default)
			)
			(layer "B.Fab")
		)
		(fp_line
			(start 0.67945 -0.305054)
			(end 0.12065 -0.305054)
			(stroke
				(width 0.1)
				(type default)
			)
			(layer "B.Fab")
		)
		(fp_line
			(start 0.12065 0.3048)
			(end 0.67945 0.3048)
			(stroke
				(width 0.1)
				(type default)
			)
			(layer "B.Fab")
		)
		(fp_line
			(start 0.12065 0.2794)
			(end 0.12065 0.3048)
			(stroke
				(width 0.1)
				(type default)
			)
			(layer "B.Fab")
		)
		(fp_line
			(start 0.12065 -0.2794)
			(end -0.12065 -0.2794)
			(stroke
				(width 0.1)
				(type default)
			)
			(layer "B.Fab")
		)
		(fp_line
			(start 0.12065 -0.305054)
			(end 0.12065 -0.2794)
			(stroke
				(width 0.1)
				(type default)
			)
			(layer "B.Fab")
		)
		(fp_line
			(start -0.120396 0.3048)
			(end -0.120396 0.2794)
			(stroke
				(width 0.1)
				(type default)
			)
			(layer "B.Fab")
		)
		(fp_line
			(start -0.120396 0.2794)
			(end 0.12065 0.2794)
			(stroke
				(width 0.1)
				(type default)
			)
			(layer "B.Fab")
		)
		(fp_line
			(start -0.12065 -0.2794)
			(end -0.12065 -0.3048)
			(stroke
				(width 0.1)
				(type default)
			)
			(layer "B.Fab")
		)
		(fp_line
			(start -0.12065 -0.3048)
			(end -0.67945 -0.3048)
			(stroke
				(width 0.1)
				(type default)
			)
			(layer "B.Fab")
		)
		(fp_line
			(start -0.67945 0.3048)
			(end -0.120396 0.3048)
			(stroke
				(width 0.1)
				(type default)
			)
			(layer "B.Fab")
		)
		(fp_line
			(start -0.67945 -0.3048)
			(end -0.67945 0.3048)
			(stroke
				(width 0.1)
				(type default)
			)
			(layer "B.Fab")
		)
		(pad "1" smd circle
			(at 0.40005 0)
			(size 0 0)
			(layers "B.Cu" "B.Mask" "B.Paste")
			(net "PVDDCR_CPU0_P0_TEMP0")
		)
		(pad "2" smd circle
			(at -0.40005 0)
			(size 0 0)
			(layers "B.Cu" "B.Mask" "B.Paste")
			(net "GND")
		)
	)
	(footprint ""
		(layer "B.Cu")
		(at 367.101628 -423.57675 180)
		(property "Reference" "R688"
			(at 0 0 0)
			(layer "B.SilkS")
			(hide yes)
			(effects
				(font
					(size 1.27 1.27)
				)
				(justify mirror)
			)
		)
		(property "Value" ""
			(at 0 0 0)
			(layer "B.Fab")
			(effects
				(font
					(size 1.27 1.27)
				)
				(justify mirror)
			)
		)
		(duplicate_pad_numbers_are_jumpers no)
		(fp_line
			(start 0.32512 0.175006)
			(end 0.32512 -0.175006)
			(stroke
				(width 0.1)
				(type default)
			)
			(layer "B.Fab")
		)
		(fp_line
			(start 0.32512 -0.175006)
			(end -0.32512 -0.175006)
			(stroke
				(width 0.1)
				(type default)
			)
			(layer "B.Fab")
		)
		(fp_line
			(start -0.32512 0.175006)
			(end 0.32512 0.175006)
			(stroke
				(width 0.1)
				(type default)
			)
			(layer "B.Fab")
		)
		(fp_line
			(start -0.32512 -0.175006)
			(end -0.32512 0.175006)
			(stroke
				(width 0.1)
				(type default)
			)
			(layer "B.Fab")
		)
		(pad "1" smd rect
			(at 0.2667 0)
			(size 0.3048 0.381)
			(layers "B.Cu" "B.Mask" "B.Paste")
			(net "SMB_RT_CPU0_P3_ROM_R_SDA")
		)
		(pad "2" smd rect
			(at -0.2667 0 180)
			(size 0.3048 0.381)
			(layers "B.Cu" "B.Mask" "B.Paste")
			(net "SMB_RT_CPU0_P3_ROM_SDA")
		)
	)
	(footprint ""
		(layer "B.Cu")
		(at 234.4801 -226.822 180)
		(property "Reference" "R140"
			(at 0 0 0)
			(layer "B.SilkS")
			(hide yes)
			(effects
				(font
					(size 1.27 1.27)
				)
				(justify mirror)
			)
		)
		(property "Value" ""
			(at 0 0 0)
			(layer "B.Fab")
			(effects
				(font
					(size 1.27 1.27)
				)
				(justify mirror)
			)
		)
		(duplicate_pad_numbers_are_jumpers no)
		(fp_line
			(start 0.7874 0.4064)
			(end 0.7874 -0.4064)
			(stroke
				(width 0.1524)
				(type default)
			)
			(layer "B.SilkS")
		)
		(fp_line
			(start 0.7874 -0.4064)
			(end -0.7874 -0.4064)
			(stroke
				(width 0.1524)
				(type default)
			)
			(layer "B.SilkS")
		)
		(fp_line
			(start -0.7874 0.4064)
			(end 0.7874 0.4064)
			(stroke
				(width 0.1524)
				(type default)
			)
			(layer "B.SilkS")
		)
		(fp_line
			(start -0.7874 -0.4064)
			(end -0.7874 0.4064)
			(stroke
				(width 0.1524)
				(type default)
			)
			(layer "B.SilkS")
		)
		(fp_line
			(start 0.67945 0.3048)
			(end 0.67945 -0.305054)
			(stroke
				(width 0.1)
				(type default)
			)
			(layer "B.Fab")
		)
		(fp_line
			(start 0.67945 -0.305054)
			(end 0.12065 -0.305054)
			(stroke
				(width 0.1)
				(type default)
			)
			(layer "B.Fab")
		)
		(fp_line
			(start 0.12065 0.3048)
			(end 0.67945 0.3048)
			(stroke
				(width 0.1)
				(type default)
			)
			(layer "B.Fab")
		)
		(fp_line
			(start 0.12065 0.2794)
			(end 0.12065 0.3048)
			(stroke
				(width 0.1)
				(type default)
			)
			(layer "B.Fab")
		)
		(fp_line
			(start 0.12065 -0.2794)
			(end -0.12065 -0.2794)
			(stroke
				(width 0.1)
				(type default)
			)
			(layer "B.Fab")
		)
		(fp_line
			(start 0.12065 -0.305054)
			(end 0.12065 -0.2794)
			(stroke
				(width 0.1)
				(type default)
			)
			(layer "B.Fab")
		)
		(fp_line
			(start -0.120396 0.3048)
			(end -0.120396 0.2794)
			(stroke
				(width 0.1)
				(type default)
			)
			(layer "B.Fab")
		)
		(fp_line
			(start -0.120396 0.2794)
			(end 0.12065 0.2794)
			(stroke
				(width 0.1)
				(type default)
			)
			(layer "B.Fab")
		)
		(fp_line
			(start -0.12065 -0.2794)
			(end -0.12065 -0.3048)
			(stroke
				(width 0.1)
				(type default)
			)
			(layer "B.Fab")
		)
		(fp_line
			(start -0.12065 -0.3048)
			(end -0.67945 -0.3048)
			(stroke
				(width 0.1)
				(type default)
			)
			(layer "B.Fab")
		)
		(fp_line
			(start -0.67945 0.3048)
			(end -0.120396 0.3048)
			(stroke
				(width 0.1)
				(type default)
			)
			(layer "B.Fab")
		)
		(fp_line
			(start -0.67945 -0.3048)
			(end -0.67945 0.3048)
			(stroke
				(width 0.1)
				(type default)
			)
			(layer "B.Fab")
		)
		(pad "1" smd rect
			(at 0.40005 0 180)
			(size 0.4572 0.508)
			(layers "B.Cu" "B.Mask" "B.Paste")
			(net "SMB_CPU0_CPU1_APML_SCL")
		)
		(pad "2" smd rect
			(at -0.40005 0 180)
			(size 0.4572 0.508)
			(layers "B.Cu" "B.Mask" "B.Paste")
			(net "SMB_CPU0_CPU1_APML_BUF1_SCL")
		)
	)
)
